# T6G (Grand Teton) — schematic netlist excerpt (pin names and nets, part order shuffled) for the footprints in the layout excerpt that follows; sources: Cadence DE-HDL packaged netlist, KiCad conversion of 04192023_DAF0TMB3IC0_F0TG_MB_C_brd_V02_OCP.brd

PC594  Q_CAP  0.22UF 16V 10% X7R  pkg 0402  page 198 : A = SW_PVDDCR_SOC_P0_BOOT2_RC ; B = SW_PVDDCR_SOC_P0_PH2
C6500  Q_CAP  0.1UF 25V 10% X7R  pkg 0402  page 188 : A = P3V3 ; B = GND
R1478  Q_RES  1K 1% EMPTY  pkg 0201LF  page 298 : A = P1V8_CPU0_RT_1D ; B = JTAG_TDO_RT_CPU0_P2

(kicad_pcb
	(version 20260206)
	(generator "pcbnew")
	(generator_version "10.0")
	(general
		(thickness 1.6)
		(legacy_teardrops no)
	)
	(paper "A4")
	(title_block
		(title "04192023_DAF0TMB3IC0_F0TG_MB_C_brd_V02_OCP.brd")
		(comment 1 "Grand Teton / footprints 822-824 of 8354")
	)
	(layers
		(0 "F.Cu" signal "TOP")
		(4 "In1.Cu" signal "GND")
		(6 "In2.Cu" signal "IN1")
		(8 "In3.Cu" signal "GND1")
		(10 "In4.Cu" signal "IN2")
		(12 "In5.Cu" signal "GND2")
		(14 "In6.Cu" signal "IN3")
		(16 "In7.Cu" signal "GND3")
		(18 "In8.Cu" signal "VCC")
		(20 "In9.Cu" signal "VCC1")
		(22 "In10.Cu" signal "GND4")
		(24 "In11.Cu" signal "IN4")
		(26 "In12.Cu" signal "GND5")
		(28 "In13.Cu" signal "IN5")
		(30 "In14.Cu" signal "GND6")
		(32 "In15.Cu" signal "IN6")
		(34 "In16.Cu" signal "GND7")
		(2 "B.Cu" signal "BOTTOM")
		(9 "F.Adhes" user "F.Adhesive")
		(11 "B.Adhes" user "B.Adhesive")
		(13 "F.Paste" user "Package Geometry/Pastemask Top")
		(15 "B.Paste" user "Package Geometry/Pastemask Bottom")
		(5 "F.SilkS" user "Ref Des/Silkscreen Top")
		(7 "B.SilkS" user "Ref Des/Silkscreen Bottom")
		(1 "F.Mask" user "Board Geometry/Soldermask Top")
		(3 "B.Mask" user "Board Geometry/Soldermask Bottom")
		(17 "Dwgs.User" user "User.Drawings")
		(19 "Cmts.User" user "User.Comments")
		(21 "Eco1.User" user "User.Eco1")
		(23 "Eco2.User" user "User.Eco2")
		(25 "Edge.Cuts" user "Board Geometry/Outline")
		(27 "Margin" user)
		(31 "F.CrtYd" user "Package Geometry/Place Bound Top")
		(29 "B.CrtYd" user "Package Geometry/Place Bound Bottom")
		(35 "F.Fab" user "Ref Des/Assembly Top")
		(33 "B.Fab" user "Ref Des/Assembly Bottom")
	)
	(footprint ""
		(layer "F.Cu")
		(at 118.999 -124.841 -90)
		(property "Reference" "C6500"
			(at 0 0 270)
			(layer "F.SilkS")
			(hide yes)
			(effects
				(font
					(size 1.27 1.27)
				)
			)
		)
		(property "Value" ""
			(at 0 0 270)
			(layer "F.Fab")
			(effects
				(font
					(size 1.27 1.27)
				)
			)
		)
		(duplicate_pad_numbers_are_jumpers no)
		(fp_line
			(start -0.7874 0.4064)
			(end -0.7874 -0.4064)
			(stroke
				(width 0.1524)
				(type default)
			)
			(layer "F.SilkS")
		)
		(fp_line
			(start 0.7874 0.4064)
			(end -0.7874 0.4064)
			(stroke
				(width 0.1524)
				(type default)
			)
			(layer "F.SilkS")
		)
		(fp_line
			(start -0.7874 -0.4064)
			(end 0.7874 -0.4064)
			(stroke
				(width 0.1524)
				(type default)
			)
			(layer "F.SilkS")
		)
		(fp_line
			(start 0.7874 -0.4064)
			(end 0.7874 0.4064)
			(stroke
				(width 0.1524)
				(type default)
			)
			(layer "F.SilkS")
		)
		(fp_line
			(start -0.67945 0.3048)
			(end -0.67945 -0.305054)
			(stroke
				(width 0.1)
				(type default)
			)
			(layer "F.Fab")
		)
		(fp_line
			(start -0.12065 0.3048)
			(end -0.67945 0.3048)
			(stroke
				(width 0.1)
				(type default)
			)
			(layer "F.Fab")
		)
		(fp_line
			(start 0.120396 0.3048)
			(end 0.120396 0.2794)
			(stroke
				(width 0.1)
				(type default)
			)
			(layer "F.Fab")
		)
		(fp_line
			(start 0.67945 0.3048)
			(end 0.120396 0.3048)
			(stroke
				(width 0.1)
				(type default)
			)
			(layer "F.Fab")
		)
		(fp_line
			(start -0.12065 0.2794)
			(end -0.12065 0.3048)
			(stroke
				(width 0.1)
				(type default)
			)
			(layer "F.Fab")
		)
		(fp_line
			(start 0.120396 0.2794)
			(end -0.12065 0.2794)
			(stroke
				(width 0.1)
				(type default)
			)
			(layer "F.Fab")
		)
		(fp_line
			(start -0.12065 -0.2794)
			(end 0.12065 -0.2794)
			(stroke
				(width 0.1)
				(type default)
			)
			(layer "F.Fab")
		)
		(fp_line
			(start 0.12065 -0.2794)
			(end 0.12065 -0.3048)
			(stroke
				(width 0.1)
				(type default)
			)
			(layer "F.Fab")
		)
		(fp_line
			(start 0.12065 -0.3048)
			(end 0.67945 -0.3048)
			(stroke
				(width 0.1)
				(type default)
			)
			(layer "F.Fab")
		)
		(fp_line
			(start 0.67945 -0.3048)
			(end 0.67945 0.3048)
			(stroke
				(width 0.1)
				(type default)
			)
			(layer "F.Fab")
		)
		(fp_line
			(start -0.67945 -0.305054)
			(end -0.12065 -0.305054)
			(stroke
				(width 0.1)
				(type default)
			)
			(layer "F.Fab")
		)
		(fp_line
			(start -0.12065 -0.305054)
			(end -0.12065 -0.2794)
			(stroke
				(width 0.1)
				(type default)
			)
			(layer "F.Fab")
		)
		(pad "1" smd circle
			(at -0.40005 0 270)
			(size 0 0)
			(layers "F.Cu" "F.Mask" "F.Paste")
			(net "P3V3")
		)
		(pad "2" smd circle
			(at 0.40005 0 270)
			(size 0 0)
			(layers "F.Cu" "F.Mask" "F.Paste")
			(net "GND")
		)
	)
	(footprint ""
		(layer "F.Cu")
		(at 432.308 -406.7048)
		(property "Reference" "R1478"
			(at 0 0 0)
			(layer "F.SilkS")
			(hide yes)
			(effects
				(font
					(size 1.27 1.27)
				)
			)
		)
		(property "Value" ""
			(at 0 0 0)
			(layer "F.Fab")
			(effects
				(font
					(size 1.27 1.27)
				)
			)
		)
		(duplicate_pad_numbers_are_jumpers no)
		(fp_line
			(start -0.32512 -0.175006)
			(end 0.32512 -0.175006)
			(stroke
				(width 0.1)
				(type default)
			)
			(layer "F.Fab")
		)
		(fp_line
			(start -0.32512 0.175006)
			(end -0.32512 -0.175006)
			(stroke
				(width 0.1)
				(type default)
			)
			(layer "F.Fab")
		)
		(fp_line
			(start 0.32512 -0.175006)
			(end 0.32512 0.175006)
			(stroke
				(width 0.1)
				(type default)
			)
			(layer "F.Fab")
		)
		(fp_line
			(start 0.32512 0.175006)
			(end -0.32512 0.175006)
			(stroke
				(width 0.1)
				(type default)
			)
			(layer "F.Fab")
		)
		(pad "1" smd rect
			(at -0.2667 0)
			(size 0.3048 0.381)
			(layers "F.Cu" "F.Mask" "F.Paste")
			(net "P1V8_CPU0_RT_1D")
		)
		(pad "2" smd rect
			(at 0.2667 0 180)
			(size 0.3048 0.381)
			(layers "F.Cu" "F.Mask" "F.Paste")
			(net "JTAG_TDO_RT_CPU0_P2")
		)
	)
	(footprint ""
		(layer "F.Cu")
		(at 404.361904 -163.942014 90)
		(property "Reference" "PC594"
			(at 0 0 90)
			(layer "F.SilkS")
			(hide yes)
			(effects
				(font
					(size 1.27 1.27)
				)
			)
		)
		(property "Value" ""
			(at 0 0 90)
			(layer "F.Fab")
			(effects
				(font
					(size 1.27 1.27)
				)
			)
		)
		(duplicate_pad_numbers_are_jumpers no)
		(fp_line
			(start 0.7874 -0.4064)
			(end 0.7874 0.4064)
			(stroke
				(width 0.1524)
				(type default)
			)
			(layer "F.SilkS")
		)
		(fp_line
			(start -0.7874 -0.4064)
			(end 0.7874 -0.4064)
			(stroke
				(width 0.1524)
				(type default)
			)
			(layer "F.SilkS")
		)
		(fp_line
			(start 0.7874 0.4064)
			(end -0.7874 0.4064)
			(stroke
				(width 0.1524)
				(type default)
			)
			(layer "F.SilkS")
		)
		(fp_line
			(start -0.7874 0.4064)
			(end -0.7874 -0.4064)
			(stroke
				(width 0.1524)
				(type default)
			)
			(layer "F.SilkS")
		)
		(fp_line
			(start -0.12065 -0.305054)
			(end -0.12065 -0.2794)
			(stroke
				(width 0.1)
				(type default)
			)
			(layer "F.Fab")
		)
		(fp_line
			(start -0.67945 -0.305054)
			(end -0.12065 -0.305054)
			(stroke
				(width 0.1)
				(type default)
			)
			(layer "F.Fab")
		)
		(fp_line
			(start 0.67945 -0.3048)
			(end 0.67945 0.3048)
			(stroke
				(width 0.1)
				(type default)
			)
			(layer "F.Fab")
		)
		(fp_line
			(start 0.12065 -0.3048)
			(end 0.67945 -0.3048)
			(stroke
				(width 0.1)
				(type default)
			)
			(layer "F.Fab")
		)
		(fp_line
			(start 0.12065 -0.2794)
			(end 0.12065 -0.3048)
			(stroke
				(width 0.1)
				(type default)
			)
			(layer "F.Fab")
		)
		(fp_line
			(start -0.12065 -0.2794)
			(end 0.12065 -0.2794)
			(stroke
				(width 0.1)
				(type default)
			)
			(layer "F.Fab")
		)
		(fp_line
			(start 0.120396 0.2794)
			(end -0.12065 0.2794)
			(stroke
				(width 0.1)
				(type default)
			)
			(layer "F.Fab")
		)
		(fp_line
			(start -0.12065 0.2794)
			(end -0.12065 0.3048)
			(stroke
				(width 0.1)
				(type default)
			)
			(layer "F.Fab")
		)
		(fp_line
			(start 0.67945 0.3048)
			(end 0.120396 0.3048)
			(stroke
				(width 0.1)
				(type default)
			)
			(layer "F.Fab")
		)
		(fp_line
			(start 0.120396 0.3048)
			(end 0.120396 0.2794)
			(stroke
				(width 0.1)
				(type default)
			)
			(layer "F.Fab")
		)
		(fp_line
			(start -0.12065 0.3048)
			(end -0.67945 0.3048)
			(stroke
				(width 0.1)
				(type default)
			)
			(layer "F.Fab")
		)
		(fp_line
			(start -0.67945 0.3048)
			(end -0.67945 -0.305054)
			(stroke
				(width 0.1)
				(type default)
			)
			(layer "F.Fab")
		)
		(pad "1" smd circle
			(at -0.40005 0 90)
			(size 0 0)
			(layers "F.Cu" "F.Mask" "F.Paste")
			(net "SW_PVDDCR_SOC_P0_BOOT2_RC")
		)
		(pad "2" smd circle
			(at 0.40005 0 90)
			(size 0 0)
			(layers "F.Cu" "F.Mask" "F.Paste")
			(net "SW_PVDDCR_SOC_P0_PH2")
		)
	)
)
